FILE_TYPE=LIBRARY_PARTS;
primitive 'ISL69260IRAZT';
  pin
    'CS7':
      PIN_NUMBER='(23)';
      INPUT_LOAD='(-0.01,0.01)';
    'VCC':
      PIN_NUMBER='(39)';
      PINUSE='POWER';
      NO_LOAD_CHECK='Both';
      NO_IO_CHECK='Both';
      NO_ASSERT_CHECK='TRUE';
      NO_DIR_CHECK='TRUE';
      ALLOW_CONNECT='TRUE';
    'EN1':
      PIN_NUMBER='(20)';
      INPUT_LOAD='(-0.01,0.01)';
    'PMSCL':
      PIN_NUMBER='(10)';
      INPUT_LOAD='(-0.01,0.01)';
    'SVDATA':
      PIN_NUMBER='(18)';
      BIDIRECTIONAL='TRUE';
      INPUT_LOAD='(-0.01,0.01)';
      OUTPUT_LOAD='(1.0,-1.0)';
    'CS6':
      PIN_NUMBER='(24)';
      INPUT_LOAD='(-0.01,0.01)';
    'NSVALERT#':
      PIN_NUMBER='(19)';
      OUTPUT_LOAD='(1.0,-1.0)';
    'NVRHOT#':
      PIN_NUMBER='(14)';
      OUTPUT_LOAD='(1.0,-1.0)';
    'CS5':
      PIN_NUMBER='(25)';
      INPUT_LOAD='(-0.01,0.01)';
    'CS4':
      PIN_NUMBER='(26)';
      INPUT_LOAD='(-0.01,0.01)';
    'PG1':
      PIN_NUMBER='(16)';
      OUTPUT_LOAD='(1.0,-1.0)';
    'SVCLK':
      PIN_NUMBER='(17)';
      INPUT_LOAD='(-0.01,0.01)';
    'NPMALERT#':
      PIN_NUMBER='(11)';
      OUTPUT_LOAD='(1.0,-1.0)';
    'EN0':
      PIN_NUMBER='(13)';
      INPUT_LOAD='(-0.01,0.01)';
    'RGND0':
      PIN_NUMBER='(22)';
      INPUT_LOAD='(-0.01,0.01)';
    'PMSDA':
      PIN_NUMBER='(9)';
      BIDIRECTIONAL='TRUE';
      INPUT_LOAD='(-0.01,0.01)';
      OUTPUT_LOAD='(1.0,-1.0)';
    'PWM4':
      PIN_NUMBER='(5)';
      OUTPUT_LOAD='(1.0,-1.0)';
    'PWM5':
      PIN_NUMBER='(6)';
      OUTPUT_LOAD='(1.0,-1.0)';
    'VSEN0':
      PIN_NUMBER='(21)';
      INPUT_LOAD='(-0.01,0.01)';
    'PWM1':
      PIN_NUMBER='(2)';
      OUTPUT_LOAD='(1.0,-1.0)';
    'PG0':
      PIN_NUMBER='(12)';
      OUTPUT_LOAD='(1.0,-1.0)';
    'PWM6':
      PIN_NUMBER='(7)';
      OUTPUT_LOAD='(1.0,-1.0)';
    'VCCS':
      PIN_NUMBER='(40)';
      PINUSE='POWER';
      NO_LOAD_CHECK='Both';
      NO_IO_CHECK='Both';
      NO_ASSERT_CHECK='TRUE';
      NO_DIR_CHECK='TRUE';
      ALLOW_CONNECT='TRUE';
    'VMON||IINSEN||VSYS||ISYS':
      PIN_NUMBER='(37)';
      INPUT_LOAD='(-0.01,0.01)';
    'VINSEN||VSYS':
      PIN_NUMBER='(38)';
      INPUT_LOAD='(-0.01,0.01)';
    'TEMP1||ISYS':
      PIN_NUMBER='(36)';
      INPUT_LOAD='(-0.01,0.01)';
    'NPINALERT#||NPSYSCRIT#':
      PIN_NUMBER='(15)';
      OUTPUT_LOAD='(1.0,-1.0)';
    'VSEN1':
      PIN_NUMBER='(32)';
      INPUT_LOAD='(-0.01,0.01)';
    'RGND1':
      PIN_NUMBER='(31)';
      INPUT_LOAD='(-0.01,0.01)';
    'CS1':
      PIN_NUMBER='(29)';
      INPUT_LOAD='(-0.01,0.01)';
    'PWM7':
      PIN_NUMBER='(8)';
      OUTPUT_LOAD='(1.0,-1.0)';
    'PWM3':
      PIN_NUMBER='(4)';
      OUTPUT_LOAD='(1.0,-1.0)';
    'CS3':
      PIN_NUMBER='(27)';
      INPUT_LOAD='(-0.01,0.01)';
    'PWM2':
      PIN_NUMBER='(3)';
      OUTPUT_LOAD='(1.0,-1.0)';
    'CS2':
      PIN_NUMBER='(28)';
      INPUT_LOAD='(-0.01,0.01)';
    'CFP':
      PIN_NUMBER='(33)';
      OUTPUT_LOAD='(1.0,-1.0)';
    'TH_GND':
      PIN_NUMBER='(TH)';
      PINUSE='POWER';
      NO_LOAD_CHECK='Both';
      NO_IO_CHECK='Both';
      NO_ASSERT_CHECK='TRUE';
      NO_DIR_CHECK='TRUE';
      ALLOW_CONNECT='TRUE';
    'ADDR_CFG':
      PIN_NUMBER='(34)';
      INPUT_LOAD='(-0.01,0.01)';
    'TEMP0':
      PIN_NUMBER='(35)';
      INPUT_LOAD='(-0.01,0.01)';
    'PWM0':
      PIN_NUMBER='(1)';
      OUTPUT_LOAD='(1.0,-1.0)';
    'CS0':
      PIN_NUMBER='(30)';
      INPUT_LOAD='(-0.01,0.01)';
  end_pin;
  body
    PART_NAME='ISL69260IRAZT';
    BODY_NAME='ISL69260IRAZT';
    PHYS_DES_PREFIX='U';
    CLASS='IC';
  end_body;
end_primitive;

END.
